(kicad_sch (version 20230121) (generator eeschema)

  (paper "A3")

  (title_block
    (title "Data Center RDIMM DDR4 Tester")
    (date "2024-09-30")
    (rev "1.2.4")
    (comment 1 "www.antmicro.com")
    (comment 2 "Antmicro Ltd")
  )

  (text "Data Center RDIMM DDR4 Tester" (at 172.085 35.56 0)
    (effects (font (size 3.9878 3.9878) (thickness 0.7976) bold) (justify left bottom))
  )

  (symbol (lib_id "antmicroMechanicalParts:antmicro_logo") (at 167.64 281.305 0) (unit 1)
    (in_bom yes) (on_board yes) (dnp no) (fields_autoplaced)
    (property "Reference" "N2" (at 173.355 279.0125 0)
      (effects (font (size 1.27 1.27)) (justify left))
    )
    (property "Value" "antmicro_logo" (at 173.355 281.5525 0)
      (effects (font (size 1.27 1.27) (thickness 0.15)) (justify left))
    )
    (property "Footprint" "antmicro-footprints:antmicro-logo" (at 182.88 291.465 0)
      (effects (font (size 1.27 1.27) (thickness 0.15)) (justify left bottom) hide)
    )
    (property "Datasheet" "" (at 182.88 294.005 0)
      (effects (font (size 1.27 1.27) (thickness 0.15)) (justify left bottom) hide)
    )
    (property "MPN" "" (at 167.64 281.305 0)
      (effects (font (size 1.27 1.27)) hide)
    )
    (property "Manufacturer" "" (at 182.88 301.625 0)
      (effects (font (size 1.27 1.27) (thickness 0.15)) (justify left bottom) hide)
    )
    (property "Author" "Antmicro" (at 182.88 296.545 0)
      (effects (font (size 1.27 1.27) (thickness 0.15)) (justify left bottom) hide)
    )
    (property "License" "Apache-2.0" (at 182.88 299.085 0)
      (effects (font (size 1.27 1.27) (thickness 0.15)) (justify left bottom) hide)
    )
    (instances
      (project "data-center-rdimm-ddr4-tester"
        (path ""
          (reference "N2") (unit 1)
        )
      )
    )
  )

  (symbol (lib_id "antmicroMechanicalParts:oshw_logo") (at 168.275 273.685 0) (unit 1)
    (in_bom yes) (on_board yes) (dnp no) (fields_autoplaced)
    (property "Reference" "N1" (at 174.625 271.3925 0)
      (effects (font (size 1.27 1.27)) (justify left))
    )
    (property "Value" "oshw_logo" (at 174.625 273.9325 0)
      (effects (font (size 1.27 1.27) (thickness 0.15)) (justify left))
    )
    (property "Footprint" "antmicro-footprints:oshw-logo" (at 183.515 283.845 0)
      (effects (font (size 1.27 1.27) (thickness 0.15)) (justify left bottom) hide)
    )
    (property "Datasheet" "" (at 183.515 286.385 0)
      (effects (font (size 1.27 1.27) (thickness 0.15)) (justify left bottom) hide)
    )
    (property "Author" "Antmicro" (at 183.515 288.925 0)
      (effects (font (size 1.27 1.27) (thickness 0.15)) (justify left bottom) hide)
    )
    (property "License" "Apache-2.0" (at 183.515 291.465 0)
      (effects (font (size 1.27 1.27) (thickness 0.15)) (justify left bottom) hide)
    )
    (property "MPN" "" (at 168.275 273.685 0)
      (effects (font (size 1.27 1.27)) hide)
    )
    (property "Manufacturer" "" (at 183.515 294.005 0)
      (effects (font (size 1.27 1.27) (thickness 0.15)) (justify left bottom) hide)
    )
    (instances
      (project "data-center-rdimm-ddr4-tester"
        (path ""
          (reference "N1") (unit 1)
        )
      )
    )
  )

  (symbol (lib_id "antmicroFiducialMarks:Fiducial_1mm_Mask2mm") (at 208.915 265.43 0) (unit 1)
    (in_bom no) (on_board yes) (dnp no) (fields_autoplaced)
    (property "Reference" "FID1" (at 212.09 264.1599 0)
      (effects (font (size 1.27 1.27)) (justify left))
    )
    (property "Value" "Fiducial_1mm_Mask2mm" (at 212.09 266.6999 0)
      (effects (font (size 1.27 1.27) (thickness 0.15)) (justify left))
    )
    (property "Footprint" "antmicro-footprints:Fiducial_1mm_Mask2mm" (at 224.155 275.59 0)
      (effects (font (size 1.27 1.27) (thickness 0.15)) (justify left bottom) hide)
    )
    (property "Datasheet" "" (at 224.155 278.13 0)
      (effects (font (size 1.27 1.27) (thickness 0.15)) (justify left bottom) hide)
    )
    (property "MPN" "" (at 224.155 280.67 0)
      (effects (font (size 1.27 1.27) (thickness 0.15)) (justify left bottom) hide)
    )
    (property "Manufacturer" "" (at 224.155 283.21 0)
      (effects (font (size 1.27 1.27) (thickness 0.15)) (justify left bottom) hide)
    )
    (property "Author" "Antmicro" (at 224.155 285.75 0)
      (effects (font (size 1.27 1.27) (thickness 0.15)) (justify left bottom) hide)
    )
    (property "License" "Apache-2.0" (at 224.155 288.29 0)
      (effects (font (size 1.27 1.27) (thickness 0.15)) (justify left bottom) hide)
    )
    (instances
      (project "data-center-rdimm-ddr4-tester"
        (path ""
          (reference "FID1") (unit 1)
        )
      )
    )
  )

  (symbol (lib_id "antmicroFiducialMarks:Fiducial_1mm_Mask2mm") (at 250.19 265.43 0) (unit 1)
    (in_bom no) (on_board yes) (dnp no) (fields_autoplaced)
    (property "Reference" "FID3" (at 254 264.1599 0)
      (effects (font (size 1.27 1.27)) (justify left))
    )
    (property "Value" "Fiducial_1mm_Mask2mm" (at 254 266.6999 0)
      (effects (font (size 1.27 1.27) (thickness 0.15)) (justify left))
    )
    (property "Footprint" "antmicro-footprints:Fiducial_1mm_Mask2mm" (at 265.43 275.59 0)
      (effects (font (size 1.27 1.27) (thickness 0.15)) (justify left bottom) hide)
    )
    (property "Datasheet" "" (at 265.43 278.13 0)
      (effects (font (size 1.27 1.27) (thickness 0.15)) (justify left bottom) hide)
    )
    (property "MPN" "" (at 265.43 280.67 0)
      (effects (font (size 1.27 1.27) (thickness 0.15)) (justify left bottom) hide)
    )
    (property "Manufacturer" "" (at 265.43 283.21 0)
      (effects (font (size 1.27 1.27) (thickness 0.15)) (justify left bottom) hide)
    )
    (property "Author" "Antmicro" (at 265.43 285.75 0)
      (effects (font (size 1.27 1.27) (thickness 0.15)) (justify left bottom) hide)
    )
    (property "License" "Apache-2.0" (at 265.43 288.29 0)
      (effects (font (size 1.27 1.27) (thickness 0.15)) (justify left bottom) hide)
    )
    (instances
      (project "data-center-rdimm-ddr4-tester"
        (path ""
          (reference "FID3") (unit 1)
        )
      )
    )
  )

  (symbol (lib_id "antmicroFiducialMarks:Fiducial_1mm_Mask2mm") (at 208.915 278.13 0) (unit 1)
    (in_bom no) (on_board yes) (dnp no) (fields_autoplaced)
    (property "Reference" "FID5" (at 212.09 276.8599 0)
      (effects (font (size 1.27 1.27)) (justify left))
    )
    (property "Value" "Fiducial_1mm_Mask2mm" (at 212.09 279.3999 0)
      (effects (font (size 1.27 1.27) (thickness 0.15)) (justify left))
    )
    (property "Footprint" "antmicro-footprints:Fiducial_1mm_Mask2mm" (at 224.155 288.29 0)
      (effects (font (size 1.27 1.27) (thickness 0.15)) (justify left bottom) hide)
    )
    (property "Datasheet" "" (at 224.155 290.83 0)
      (effects (font (size 1.27 1.27) (thickness 0.15)) (justify left bottom) hide)
    )
    (property "MPN" "" (at 224.155 293.37 0)
      (effects (font (size 1.27 1.27) (thickness 0.15)) (justify left bottom) hide)
    )
    (property "Manufacturer" "" (at 224.155 295.91 0)
      (effects (font (size 1.27 1.27) (thickness 0.15)) (justify left bottom) hide)
    )
    (property "Author" "Antmicro" (at 224.155 298.45 0)
      (effects (font (size 1.27 1.27) (thickness 0.15)) (justify left bottom) hide)
    )
    (property "License" "Apache-2.0" (at 224.155 300.99 0)
      (effects (font (size 1.27 1.27) (thickness 0.15)) (justify left bottom) hide)
    )
    (instances
      (project "data-center-rdimm-ddr4-tester"
        (path ""
          (reference "FID5") (unit 1)
        )
      )
    )
  )

  (symbol (lib_id "data-center-rdimm-ddr4-tester:PCB_Mount_Hole_3mm_NPTH") (at 88.9 279.4 0) (unit 1)
    (in_bom yes) (on_board yes) (dnp no) (fields_autoplaced)
    (property "Reference" "MP2" (at 95.25 278.1299 0)
      (effects (font (size 1.27 1.27)) (justify left))
    )
    (property "Value" "PCB_Mount_Hole_3mm_NPTH" (at 95.25 280.6699 0)
      (effects (font (size 1.27 1.27) (thickness 0.15)) (justify left))
    )
    (property "Footprint" "data-center-rdimm-ddr4-tester-footprints:mounting-hole-3mm-NPTH" (at 106.68 287.02 0)
      (effects (font (size 1.27 1.27) (thickness 0.15)) (justify left bottom) hide)
    )
    (property "Datasheet" "" (at 106.68 289.56 0)
      (effects (font (size 1.27 1.27) (thickness 0.15)) (justify left bottom) hide)
    )
    (property "MPN" "" (at 106.68 292.1 0)
      (effects (font (size 1.27 1.27) (thickness 0.15)) (justify left bottom) hide)
    )
    (property "Manufacturer" "" (at 106.68 294.64 0)
      (effects (font (size 1.27 1.27) (thickness 0.15)) (justify left bottom) hide)
    )
    (property "Author" "Antmicro" (at 106.68 297.18 0)
      (effects (font (size 1.27 1.27) (thickness 0.15)) (justify left bottom) hide)
    )
    (property "License" "Apache-2.0" (at 106.68 299.72 0)
      (effects (font (size 1.27 1.27) (thickness 0.15)) (justify left bottom) hide)
    )
    (instances
      (project "data-center-rdimm-ddr4-tester"
        (path ""
          (reference "MP2") (unit 1)
        )
      )
    )
  )

  (symbol (lib_id "antmicroFiducialMarks:Fiducial_1mm_Mask2mm") (at 250.19 271.78 0) (unit 1)
    (in_bom no) (on_board yes) (dnp no) (fields_autoplaced)
    (property "Reference" "FID4" (at 254 270.5099 0)
      (effects (font (size 1.27 1.27)) (justify left))
    )
    (property "Value" "Fiducial_1mm_Mask2mm" (at 254 273.0499 0)
      (effects (font (size 1.27 1.27) (thickness 0.15)) (justify left))
    )
    (property "Footprint" "antmicro-footprints:Fiducial_1mm_Mask2mm" (at 265.43 281.94 0)
      (effects (font (size 1.27 1.27) (thickness 0.15)) (justify left bottom) hide)
    )
    (property "Datasheet" "" (at 265.43 284.48 0)
      (effects (font (size 1.27 1.27) (thickness 0.15)) (justify left bottom) hide)
    )
    (property "MPN" "" (at 265.43 287.02 0)
      (effects (font (size 1.27 1.27) (thickness 0.15)) (justify left bottom) hide)
    )
    (property "Manufacturer" "" (at 265.43 289.56 0)
      (effects (font (size 1.27 1.27) (thickness 0.15)) (justify left bottom) hide)
    )
    (property "Author" "Antmicro" (at 265.43 292.1 0)
      (effects (font (size 1.27 1.27) (thickness 0.15)) (justify left bottom) hide)
    )
    (property "License" "Apache-2.0" (at 265.43 294.64 0)
      (effects (font (size 1.27 1.27) (thickness 0.15)) (justify left bottom) hide)
    )
    (instances
      (project "data-center-rdimm-ddr4-tester"
        (path ""
          (reference "FID4") (unit 1)
        )
      )
    )
  )

  (symbol (lib_id "data-center-rdimm-ddr4-tester:PCB_Mount_Hole_3mm_NPTH") (at 88.9 266.7 0) (unit 1)
    (in_bom yes) (on_board yes) (dnp no) (fields_autoplaced)
    (property "Reference" "MP1" (at 95.25 265.4299 0)
      (effects (font (size 1.27 1.27)) (justify left))
    )
    (property "Value" "PCB_Mount_Hole_3mm_NPTH" (at 95.25 267.9699 0)
      (effects (font (size 1.27 1.27) (thickness 0.15)) (justify left))
    )
    (property "Footprint" "data-center-rdimm-ddr4-tester-footprints:mounting-hole-3mm-NPTH" (at 106.68 274.32 0)
      (effects (font (size 1.27 1.27) (thickness 0.15)) (justify left bottom) hide)
    )
    (property "Datasheet" "" (at 106.68 276.86 0)
      (effects (font (size 1.27 1.27) (thickness 0.15)) (justify left bottom) hide)
    )
    (property "MPN" "" (at 106.68 279.4 0)
      (effects (font (size 1.27 1.27) (thickness 0.15)) (justify left bottom) hide)
    )
    (property "Manufacturer" "" (at 106.68 281.94 0)
      (effects (font (size 1.27 1.27) (thickness 0.15)) (justify left bottom) hide)
    )
    (property "Author" "Antmicro" (at 106.68 284.48 0)
      (effects (font (size 1.27 1.27) (thickness 0.15)) (justify left bottom) hide)
    )
    (property "License" "Apache-2.0" (at 106.68 287.02 0)
      (effects (font (size 1.27 1.27) (thickness 0.15)) (justify left bottom) hide)
    )
    (instances
      (project "data-center-rdimm-ddr4-tester"
        (path ""
          (reference "MP1") (unit 1)
        )
      )
    )
  )

  (symbol (lib_id "antmicroFiducialMarks:Fiducial_1mm_Mask2mm") (at 250.19 278.765 0) (unit 1)
    (in_bom no) (on_board yes) (dnp no) (fields_autoplaced)
    (property "Reference" "FID6" (at 254 277.4949 0)
      (effects (font (size 1.27 1.27)) (justify left))
    )
    (property "Value" "Fiducial_1mm_Mask2mm" (at 254 280.0349 0)
      (effects (font (size 1.27 1.27) (thickness 0.15)) (justify left))
    )
    (property "Footprint" "antmicro-footprints:Fiducial_1mm_Mask2mm" (at 265.43 288.925 0)
      (effects (font (size 1.27 1.27) (thickness 0.15)) (justify left bottom) hide)
    )
    (property "Datasheet" "" (at 265.43 291.465 0)
      (effects (font (size 1.27 1.27) (thickness 0.15)) (justify left bottom) hide)
    )
    (property "MPN" "" (at 265.43 294.005 0)
      (effects (font (size 1.27 1.27) (thickness 0.15)) (justify left bottom) hide)
    )
    (property "Manufacturer" "" (at 265.43 296.545 0)
      (effects (font (size 1.27 1.27) (thickness 0.15)) (justify left bottom) hide)
    )
    (property "Author" "Antmicro" (at 265.43 299.085 0)
      (effects (font (size 1.27 1.27) (thickness 0.15)) (justify left bottom) hide)
    )
    (property "License" "Apache-2.0" (at 265.43 301.625 0)
      (effects (font (size 1.27 1.27) (thickness 0.15)) (justify left bottom) hide)
    )
    (instances
      (project "data-center-rdimm-ddr4-tester"
        (path ""
          (reference "FID6") (unit 1)
        )
      )
    )
  )

  (symbol (lib_id "data-center-rdimm-ddr4-tester:PCB_Mount_Hole_3mm_NPTH") (at 128.27 279.4 0) (unit 1)
    (in_bom yes) (on_board yes) (dnp no) (fields_autoplaced)
    (property "Reference" "MP4" (at 134.62 278.1299 0)
      (effects (font (size 1.27 1.27)) (justify left))
    )
    (property "Value" "PCB_Mount_Hole_3mm_NPTH" (at 134.62 280.6699 0)
      (effects (font (size 1.27 1.27) (thickness 0.15)) (justify left))
    )
    (property "Footprint" "data-center-rdimm-ddr4-tester-footprints:mounting-hole-3mm-NPTH" (at 146.05 287.02 0)
      (effects (font (size 1.27 1.27) (thickness 0.15)) (justify left bottom) hide)
    )
    (property "Datasheet" "" (at 146.05 289.56 0)
      (effects (font (size 1.27 1.27) (thickness 0.15)) (justify left bottom) hide)
    )
    (property "MPN" "" (at 146.05 292.1 0)
      (effects (font (size 1.27 1.27) (thickness 0.15)) (justify left bottom) hide)
    )
    (property "Manufacturer" "" (at 146.05 294.64 0)
      (effects (font (size 1.27 1.27) (thickness 0.15)) (justify left bottom) hide)
    )
    (property "Author" "Antmicro" (at 146.05 297.18 0)
      (effects (font (size 1.27 1.27) (thickness 0.15)) (justify left bottom) hide)
    )
    (property "License" "Apache-2.0" (at 146.05 299.72 0)
      (effects (font (size 1.27 1.27) (thickness 0.15)) (justify left bottom) hide)
    )
    (instances
      (project "data-center-rdimm-ddr4-tester"
        (path ""
          (reference "MP4") (unit 1)
        )
      )
    )
  )

  (symbol (lib_id "data-center-rdimm-ddr4-tester:PCB_Mount_Hole_3mm_NPTH") (at 128.27 266.7 0) (unit 1)
    (in_bom yes) (on_board yes) (dnp no) (fields_autoplaced)
    (property "Reference" "MP3" (at 134.62 265.4299 0)
      (effects (font (size 1.27 1.27)) (justify left))
    )
    (property "Value" "PCB_Mount_Hole_3mm_NPTH" (at 134.62 267.9699 0)
      (effects (font (size 1.27 1.27) (thickness 0.15)) (justify left))
    )
    (property "Footprint" "data-center-rdimm-ddr4-tester-footprints:mounting-hole-3mm-NPTH" (at 146.05 274.32 0)
      (effects (font (size 1.27 1.27) (thickness 0.15)) (justify left bottom) hide)
    )
    (property "Datasheet" "" (at 146.05 276.86 0)
      (effects (font (size 1.27 1.27) (thickness 0.15)) (justify left bottom) hide)
    )
    (property "MPN" "" (at 146.05 279.4 0)
      (effects (font (size 1.27 1.27) (thickness 0.15)) (justify left bottom) hide)
    )
    (property "Manufacturer" "" (at 146.05 281.94 0)
      (effects (font (size 1.27 1.27) (thickness 0.15)) (justify left bottom) hide)
    )
    (property "Author" "Antmicro" (at 146.05 284.48 0)
      (effects (font (size 1.27 1.27) (thickness 0.15)) (justify left bottom) hide)
    )
    (property "License" "Apache-2.0" (at 146.05 287.02 0)
      (effects (font (size 1.27 1.27) (thickness 0.15)) (justify left bottom) hide)
    )
    (instances
      (project "data-center-rdimm-ddr4-tester"
        (path ""
          (reference "MP3") (unit 1)
        )
      )
    )
  )

  (symbol (lib_id "data-center-rdimm-ddr4-tester:Mech_Lightpipe_Mentor_1296.2013") (at 170.815 265.43 0) (unit 1)
    (in_bom yes) (on_board yes) (dnp no) (fields_autoplaced)
    (property "Reference" "M1" (at 177.165 263.5249 0)
      (effects (font (size 1.27 1.27)) (justify left))
    )
    (property "Value" "Mech_Lightpipe_Mentor_1296.2013" (at 177.165 266.0649 0)
      (effects (font (size 1.27 1.27) (thickness 0.15)) (justify left) hide)
    )
    (property "Footprint" "data-center-rdimm-ddr4-tester-footprints:Mech_Lightpipe_Mentor_1296.2013" (at 191.135 273.05 0)
      (effects (font (size 1.27 1.27) (thickness 0.15)) (justify left bottom) hide)
    )
    (property "Datasheet" "https://docs.rs-online.com/e47b/0900766b813f6efb.pdf" (at 191.135 275.59 0)
      (effects (font (size 1.27 1.27) (thickness 0.15)) (justify left bottom) hide)
    )
    (property "Manufacturer" "MENTOR" (at 191.135 278.13 0)
      (effects (font (size 1.27 1.27) (thickness 0.15)) (justify left bottom) hide)
    )
    (property "MPN" "1296.2013" (at 177.165 266.0649 0)
      (effects (font (size 1.27 1.27) (thickness 0.15)) (justify left))
    )
    (property "Author" "Antmicro" (at 191.135 283.21 0)
      (effects (font (size 1.27 1.27) (thickness 0.15)) (justify left bottom) hide)
    )
    (property "License" "Apache-2.0" (at 191.135 285.75 0)
      (effects (font (size 1.27 1.27) (thickness 0.15)) (justify left bottom) hide)
    )
    (instances
      (project "data-center-rdimm-ddr4-tester"
        (path ""
          (reference "M1") (unit 1)
        )
      )
    )
  )

  (symbol (lib_id "antmicroFiducialMarks:Fiducial_1mm_Mask2mm") (at 208.915 271.78 0) (unit 1)
    (in_bom no) (on_board yes) (dnp no) (fields_autoplaced)
    (property "Reference" "FID2" (at 212.09 270.5099 0)
      (effects (font (size 1.27 1.27)) (justify left))
    )
    (property "Value" "Fiducial_1mm_Mask2mm" (at 212.09 273.0499 0)
      (effects (font (size 1.27 1.27) (thickness 0.15)) (justify left))
    )
    (property "Footprint" "antmicro-footprints:Fiducial_1mm_Mask2mm" (at 224.155 281.94 0)
      (effects (font (size 1.27 1.27) (thickness 0.15)) (justify left bottom) hide)
    )
    (property "Datasheet" "" (at 224.155 284.48 0)
      (effects (font (size 1.27 1.27) (thickness 0.15)) (justify left bottom) hide)
    )
    (property "MPN" "" (at 224.155 287.02 0)
      (effects (font (size 1.27 1.27) (thickness 0.15)) (justify left bottom) hide)
    )
    (property "Manufacturer" "" (at 224.155 289.56 0)
      (effects (font (size 1.27 1.27) (thickness 0.15)) (justify left bottom) hide)
    )
    (property "Author" "Antmicro" (at 224.155 292.1 0)
      (effects (font (size 1.27 1.27) (thickness 0.15)) (justify left bottom) hide)
    )
    (property "License" "Apache-2.0" (at 224.155 294.64 0)
      (effects (font (size 1.27 1.27) (thickness 0.15)) (justify left bottom) hide)
    )
    (instances
      (project "data-center-rdimm-ddr4-tester"
        (path ""
          (reference "FID2") (unit 1)
        )
      )
    )
  )

  (sheet (at 213.995 176.53) (size 40.005 20.32) (fields_autoplaced)
    (stroke (width 0) (type solid))
    (fill (color 0 0 0 0.0000))
    (property "Sheetname" "Ethernet" (at 213.995 175.4501 0)
      (effects (font (size 2.0066 2.0066)) (justify left bottom))
    )
    (property "Sheetfile" "ethernet.kicad_sch" (at 213.995 197.7292 0)
      (effects (font (size 2.0066 2.0066)) (justify left top))
    )
    (instances
      (project "data-center-rdimm-ddr4-tester"
        (path "" (page "8"))
      )
    )
  )

  (sheet (at 89.535 213.995) (size 40.005 20.32) (fields_autoplaced)
    (stroke (width 0) (type solid))
    (fill (color 0 0 0 0.0000))
    (property "Sheetname" "Config SPI flash" (at 89.535 212.9151 0)
      (effects (font (size 2.0066 2.0066)) (justify left bottom))
    )
    (property "Sheetfile" "config-spi.kicad_sch" (at 89.535 235.1942 0)
      (effects (font (size 2.0066 2.0066)) (justify left top))
    )
    (instances
      (project "data-center-rdimm-ddr4-tester"
        (path "" (page "3"))
      )
    )
  )

  (sheet (at 71.755 176.53) (size 40.005 20.32) (fields_autoplaced)
    (stroke (width 0) (type solid))
    (fill (color 0 0 0 0.0000))
    (property "Sheetname" "HyperRAM" (at 71.755 175.4501 0)
      (effects (font (size 2.0066 2.0066)) (justify left bottom))
    )
    (property "Sheetfile" "hyperram.kicad_sch" (at 71.755 197.7292 0)
      (effects (font (size 2.0066 2.0066)) (justify left top))
    )
    (instances
      (project "data-center-rdimm-ddr4-tester"
        (path "" (page "2"))
      )
    )
  )

  (sheet (at 139.065 213.995) (size 40.005 20.32) (fields_autoplaced)
    (stroke (width 0) (type solid))
    (fill (color 0 0 0 0.0000))
    (property "Sheetname" "FPGA power" (at 139.065 212.9151 0)
      (effects (font (size 2.0066 2.0066)) (justify left bottom))
    )
    (property "Sheetfile" "fpga-power.kicad_sch" (at 139.065 235.1942 0)
      (effects (font (size 2.0066 2.0066)) (justify left top))
    )
    (instances
      (project "data-center-rdimm-ddr4-tester"
        (path "" (page "5"))
      )
    )
  )

  (sheet (at 166.37 176.53) (size 40.005 20.32) (fields_autoplaced)
    (stroke (width 0) (type solid))
    (fill (color 0 0 0 0.0000))
    (property "Sheetname" "Interfaces" (at 166.37 175.4501 0)
      (effects (font (size 2.0066 2.0066)) (justify left bottom))
    )
    (property "Sheetfile" "interfaces.kicad_sch" (at 166.37 197.7292 0)
      (effects (font (size 2.0066 2.0066)) (justify left top))
    )
    (instances
      (project "data-center-rdimm-ddr4-tester"
        (path "" (page "6"))
      )
    )
  )

  (sheet (at 261.62 176.53) (size 40.005 20.32) (fields_autoplaced)
    (stroke (width 0) (type solid))
    (fill (color 0 0 0 0.0000))
    (property "Sheetname" "Supply" (at 261.62 175.4501 0)
      (effects (font (size 2.0066 2.0066)) (justify left bottom))
    )
    (property "Sheetfile" "supply.kicad_sch" (at 261.62 197.7292 0)
      (effects (font (size 2.0066 2.0066)) (justify left top))
    )
    (instances
      (project "data-center-rdimm-ddr4-tester"
        (path "" (page "10"))
      )
    )
  )

  (sheet (at 119.38 176.53) (size 40.005 20.32) (fields_autoplaced)
    (stroke (width 0) (type solid))
    (fill (color 0 0 0 0.0000))
    (property "Sheetname" "DDR4" (at 119.38 175.4501 0)
      (effects (font (size 2.0066 2.0066)) (justify left bottom))
    )
    (property "Sheetfile" "DDR4.kicad_sch" (at 119.38 197.7292 0)
      (effects (font (size 2.0066 2.0066)) (justify left top))
    )
    (instances
      (project "data-center-rdimm-ddr4-tester"
        (path "" (page "4"))
      )
    )
  )

  (sheet (at 187.96 213.995) (size 40.005 20.32) (fields_autoplaced)
    (stroke (width 0) (type solid))
    (fill (color 0 0 0 0.0000))
    (property "Sheetname" "FPGA banks 12-15" (at 187.96 212.9151 0)
      (effects (font (size 2.0066 2.0066)) (justify left bottom))
    )
    (property "Sheetfile" "fpga-banks-12-15.kicad_sch" (at 187.96 235.1942 0)
      (effects (font (size 2.0066 2.0066)) (justify left top))
    )
    (instances
      (project "data-center-rdimm-ddr4-tester"
        (path "" (page "7"))
      )
    )
  )

  (sheet (at 243.84 213.995) (size 40.005 20.32) (fields_autoplaced)
    (stroke (width 0) (type solid))
    (fill (color 0 0 0 0.0000))
    (property "Sheetname" "FPGA banks 16-34" (at 243.84 212.9151 0)
      (effects (font (size 2.0066 2.0066)) (justify left bottom))
    )
    (property "Sheetfile" "fpga-banks-16-34.kicad_sch" (at 243.84 235.1942 0)
      (effects (font (size 2.0066 2.0066)) (justify left top))
    )
    (instances
      (project "data-center-rdimm-ddr4-tester"
        (path "" (page "9"))
      )
    )
  )

  (sheet (at 300.99 213.995) (size 40.005 20.32) (fields_autoplaced)
    (stroke (width 0.1524) (type solid))
    (fill (color 0 0 0 0.0000))
    (property "Sheetname" "FPGA banks 115-116" (at 300.99 212.9151 0)
      (effects (font (size 2.0066 2.0066)) (justify left bottom))
    )
    (property "Sheetfile" "pcie.kicad_sch" (at 300.99 235.1942 0)
      (effects (font (size 2.0066 2.0066)) (justify left top))
    )
    (instances
      (project "data-center-rdimm-ddr4-tester"
        (path "" (page "11"))
      )
    )
  )

  (sheet (at 312.42 176.53) (size 40.64 20.32) (fields_autoplaced)
    (stroke (width 0.1524) (type solid))
    (fill (color 0 0 0 0.0000))
    (property "Sheetname" "FMC HPC" (at 312.42 175.4534 0)
      (effects (font (size 2 2)) (justify left bottom))
    )
    (property "Sheetfile" "fmc_hpc.kicad_sch" (at 312.42 197.4346 0)
      (effects (font (size 1.27 1.27)) (justify left top))
    )
    (instances
      (project "data-center-rdimm-ddr4-tester"
        (path "" (page "12"))
      )
    )
  )

  (sheet_instances
    (path "/" (page "1"))
  )
)
